#ISCELL
  mstr_symbols cad_note *
  *
#ISCELL
  mstr_symbols intel_corp_bpage *
  *
#CELL
  mstr_discrete res *
  page269_i10
#CELL
  mstr_discrete res *
  page269_i11
#CELL
  mstr_discrete res *
  page269_i12
#CELL
  mstr_discrete res *
  page269_i13
#ISCELL
  mstr_symbols gnd *
  page269_i14
#ISCELL
  mstr_symbols p3v3_stby *
  page269_i15
#ISCELL
  mstr_standard offpage *
  page269_i16
#ISCELL
  mstr_standard offpage *
  page269_i17
#CELL
  mstr_discrete res *
  page269_i18
#CELL
  mstr_discrete res *
  page269_i19
#CELL
  mstr_discrete res *
  page269_i20
#CELL
  mstr_discrete res *
  page269_i21
#CELL
  mstr_discrete res *
  page269_i22
#ISCELL
  mstr_symbols gnd *
  page269_i23
#CELL
  mstr_discrete res *
  page269_i24
#ISCELL
  mstr_symbols p3v3_stby *
  page269_i25
#CELL
  dev_discrete cap_a *
  page269_i26
#ISCELL
  mstr_symbols gnd *
  page269_i27
#ISCELL
  mstr_symbols p1v05_pch_stby *
  page269_i28
#ISCELL
  mstr_symbols gnd *
  page269_i29
#ISCELL
  mstr_symbols gnd *
  page269_i31
#CELL
  mstr_discrete cap *
  page269_i32
#CELL
  mstr_ttl ttl3126 *
  page269_i33
#ISCELL
  mstr_standard offpage *
  page269_i39
#CELL
  mstr_discrete res *
  page269_i4
#ISCELL
  mstr_standard offpage *
  page269_i40
#ISCELL
  mstr_standard offpage *
  page269_i41
#ISCELL
  mstr_standard offpage *
  page269_i45
#ISCELL
  mstr_standard offpage *
  page269_i46
#ISCELL
  mstr_standard offpage *
  page269_i47
#ISCELL
  mstr_standard offpage *
  page269_i48
#CELL
  mstr_digital gtl2014 *
  page269_i49
#ISCELL
  mstr_standard offpage *
  page269_i50
#ISCELL
  mstr_standard offpage *
  page269_i51
#ISCELL
  mstr_standard offpage *
  page269_i52
#CELL
  w_hdl max4564eka-gp *
  page269_i53
#ISCELL
  mstr_symbols gnd *
  page269_i54
#CELL
  dev_discrete cap_a *
  page269_i56
#ISCELL
  mstr_symbols gnd *
  page269_i57
#ISCELL
  mstr_symbols p3v3_stby *
  page269_i58
#ISCELL
  mstr_standard offpage *
  page269_i59
#ISCELL
  mstr_symbols p3v3_stby *
  page269_i60
#CELL
  mstr_ttl ttl1g08 *
  page269_i61
#CELL
  dev_discrete cap_a *
  page269_i62
#ISCELL
  mstr_symbols gnd *
  page269_i63
#ISCELL
  mstr_symbols p3v3_stby *
  page269_i64
#ISCELL
  mstr_standard offpage *
  page269_i65
#ISCELL
  mstr_standard offpage *
  page269_i66
#ISCELL
  mstr_standard offpage *
  page269_i67
#ISCELL
  mstr_symbols gnd *
  page269_i68
#ISCELL
  mstr_standard offpage *
  page269_i69
#ISCELL
  mstr_standard offpage *
  page269_i70
#CELL
  w_hdl blm15ag121sn-1gp *
  page269_i71
#CELL
  w_hdl blm15ag121sn-1gp *
  page269_i72
#CELL
  w_hdl blm15ag121sn-1gp *
  page269_i73
#CELL
  w_hdl blm15ag121sn-1gp *
  page269_i74
#CELL
  w_hdl blm15ag121sn-1gp *
  page269_i75
#CELL
  mstr_ttl ttl1g126_a *
  page269_i76
#ISCELL
  mstr_standard offpage *
  page269_i77
#ISCELL
  mstr_symbols gnd *
  page269_i78
#CELL
  dev_discrete cap_a *
  page269_i79
#ISCELL
  mstr_symbols p3v3_stby *
  page269_i80
#ISCELL
  mstr_standard offpage *
  page269_i81
